# T6G (Grand Teton) — schematic netlist excerpt (pin names and nets, part order shuffled) for the footprints in the layout excerpt that follows; sources: Cadence DE-HDL packaged netlist, KiCad conversion of 04192023_DAF0TMB3IC0_F0TG_MB_C_brd_V02_OCP.brd

U207  74LVC1G17GW  IC  pkg TSSOP5  page 139
  NC  = NC
  A  = RST_PERST_OCP_V3_2_BUF_N
  GND  = GND
  Y  = RST_PERST_OCP_V3_2_BUF2_N
  VCC  = P3V3_AUX

R1089  Q_RES  2.2K 5% CHIP  pkg 0402LF  page 250 : A = P3V3_AUX ; B = SMB_SENSOR_M2_P1_3V3AUX_SCL
C1548  Q_CAP_DIFFBUS  DIFF BUS_0.22UF 6.3V 20% X6S  pkg C0201  page 65 : \1\ = P5E_CPU0_G3_TX_C_DN<15> ; \2\ = P5E_CPU0_G3_TX_DN<15>

(kicad_pcb
	(version 20260206)
	(generator "pcbnew")
	(generator_version "10.0")
	(general
		(thickness 1.6)
		(legacy_teardrops no)
	)
	(paper "A4")
	(title_block
		(title "04192023_DAF0TMB3IC0_F0TG_MB_C_brd_V02_OCP.brd")
		(comment 1 "Grand Teton / footprints 869-871 of 8354")
	)
	(layers
		(0 "F.Cu" signal "TOP")
		(4 "In1.Cu" signal "GND")
		(6 "In2.Cu" signal "IN1")
		(8 "In3.Cu" signal "GND1")
		(10 "In4.Cu" signal "IN2")
		(12 "In5.Cu" signal "GND2")
		(14 "In6.Cu" signal "IN3")
		(16 "In7.Cu" signal "GND3")
		(18 "In8.Cu" signal "VCC")
		(20 "In9.Cu" signal "VCC1")
		(22 "In10.Cu" signal "GND4")
		(24 "In11.Cu" signal "IN4")
		(26 "In12.Cu" signal "GND5")
		(28 "In13.Cu" signal "IN5")
		(30 "In14.Cu" signal "GND6")
		(32 "In15.Cu" signal "IN6")
		(34 "In16.Cu" signal "GND7")
		(2 "B.Cu" signal "BOTTOM")
		(9 "F.Adhes" user "F.Adhesive")
		(11 "B.Adhes" user "B.Adhesive")
		(13 "F.Paste" user "Package Geometry/Pastemask Top")
		(15 "B.Paste" user "Package Geometry/Pastemask Bottom")
		(5 "F.SilkS" user "Ref Des/Silkscreen Top")
		(7 "B.SilkS" user "Ref Des/Silkscreen Bottom")
		(1 "F.Mask" user "Board Geometry/Soldermask Top")
		(3 "B.Mask" user "Board Geometry/Soldermask Bottom")
		(17 "Dwgs.User" user "User.Drawings")
		(19 "Cmts.User" user "User.Comments")
		(21 "Eco1.User" user "User.Eco1")
		(23 "Eco2.User" user "User.Eco2")
		(25 "Edge.Cuts" user "Board Geometry/Outline")
		(27 "Margin" user)
		(31 "F.CrtYd" user "Package Geometry/Place Bound Top")
		(29 "B.CrtYd" user "Package Geometry/Place Bound Bottom")
		(35 "F.Fab" user "Ref Des/Assembly Top")
		(33 "B.Fab" user "Ref Des/Assembly Bottom")
	)
	(footprint ""
		(layer "F.Cu")
		(at 277.352252 -114.70767)
		(property "Reference" "R1089"
			(at 0 0 0)
			(layer "F.SilkS")
			(hide yes)
			(effects
				(font
					(size 1.27 1.27)
				)
			)
		)
		(property "Value" ""
			(at 0 0 0)
			(layer "F.Fab")
			(effects
				(font
					(size 1.27 1.27)
				)
			)
		)
		(duplicate_pad_numbers_are_jumpers no)
		(fp_line
			(start -0.7874 -0.4064)
			(end 0.7874 -0.4064)
			(stroke
				(width 0.1524)
				(type default)
			)
			(layer "F.SilkS")
		)
		(fp_line
			(start -0.7874 0.4064)
			(end -0.7874 -0.4064)
			(stroke
				(width 0.1524)
				(type default)
			)
			(layer "F.SilkS")
		)
		(fp_line
			(start 0.7874 -0.4064)
			(end 0.7874 0.4064)
			(stroke
				(width 0.1524)
				(type default)
			)
			(layer "F.SilkS")
		)
		(fp_line
			(start 0.7874 0.4064)
			(end -0.7874 0.4064)
			(stroke
				(width 0.1524)
				(type default)
			)
			(layer "F.SilkS")
		)
		(fp_line
			(start -0.67945 -0.305054)
			(end -0.12065 -0.305054)
			(stroke
				(width 0.1)
				(type default)
			)
			(layer "F.Fab")
		)
		(fp_line
			(start -0.67945 0.3048)
			(end -0.67945 -0.305054)
			(stroke
				(width 0.1)
				(type default)
			)
			(layer "F.Fab")
		)
		(fp_line
			(start -0.12065 -0.305054)
			(end -0.12065 -0.2794)
			(stroke
				(width 0.1)
				(type default)
			)
			(layer "F.Fab")
		)
		(fp_line
			(start -0.12065 -0.2794)
			(end 0.12065 -0.2794)
			(stroke
				(width 0.1)
				(type default)
			)
			(layer "F.Fab")
		)
		(fp_line
			(start -0.12065 0.2794)
			(end -0.12065 0.3048)
			(stroke
				(width 0.1)
				(type default)
			)
			(layer "F.Fab")
		)
		(fp_line
			(start -0.12065 0.3048)
			(end -0.67945 0.3048)
			(stroke
				(width 0.1)
				(type default)
			)
			(layer "F.Fab")
		)
		(fp_line
			(start 0.120396 0.2794)
			(end -0.12065 0.2794)
			(stroke
				(width 0.1)
				(type default)
			)
			(layer "F.Fab")
		)
		(fp_line
			(start 0.120396 0.3048)
			(end 0.120396 0.2794)
			(stroke
				(width 0.1)
				(type default)
			)
			(layer "F.Fab")
		)
		(fp_line
			(start 0.12065 -0.3048)
			(end 0.67945 -0.3048)
			(stroke
				(width 0.1)
				(type default)
			)
			(layer "F.Fab")
		)
		(fp_line
			(start 0.12065 -0.2794)
			(end 0.12065 -0.3048)
			(stroke
				(width 0.1)
				(type default)
			)
			(layer "F.Fab")
		)
		(fp_line
			(start 0.67945 -0.3048)
			(end 0.67945 0.3048)
			(stroke
				(width 0.1)
				(type default)
			)
			(layer "F.Fab")
		)
		(fp_line
			(start 0.67945 0.3048)
			(end 0.120396 0.3048)
			(stroke
				(width 0.1)
				(type default)
			)
			(layer "F.Fab")
		)
		(pad "1" smd circle
			(at -0.40005 0)
			(size 0 0)
			(layers "F.Cu" "F.Mask" "F.Paste")
			(net "P3V3_AUX")
		)
		(pad "2" smd circle
			(at 0.40005 0)
			(size 0 0)
			(layers "F.Cu" "F.Mask" "F.Paste")
			(net "SMB_SENSOR_M2_P1_3V3AUX_SCL")
		)
	)
	(footprint ""
		(layer "F.Cu")
		(at 390.007348 -16.100298 90)
		(property "Reference" "C1548"
			(at 0 0 90)
			(layer "F.SilkS")
			(hide yes)
			(effects
				(font
					(size 1.27 1.27)
				)
			)
		)
		(property "Value" ""
			(at 0 0 90)
			(layer "F.Fab")
			(effects
				(font
					(size 1.27 1.27)
				)
			)
		)
		(duplicate_pad_numbers_are_jumpers no)
		(fp_line
			(start 0.299974 -0.150114)
			(end 0.299974 0.150114)
			(stroke
				(width 0.1)
				(type default)
			)
			(layer "F.Fab")
		)
		(fp_line
			(start -0.299974 -0.150114)
			(end 0.299974 -0.150114)
			(stroke
				(width 0.1)
				(type default)
			)
			(layer "F.Fab")
		)
		(fp_line
			(start 0.299974 0.150114)
			(end -0.299974 0.150114)
			(stroke
				(width 0.1)
				(type default)
			)
			(layer "F.Fab")
		)
		(fp_line
			(start -0.299974 0.150114)
			(end -0.299974 -0.150114)
			(stroke
				(width 0.1)
				(type default)
			)
			(layer "F.Fab")
		)
		(pad "1" smd rect
			(at -0.2667 0 90)
			(size 0.3048 0.381)
			(layers "F.Cu" "F.Mask" "F.Paste")
			(net "P5E_CPU0_G3_TX_C_DN<15>")
		)
		(pad "2" smd rect
			(at 0.2667 0 90)
			(size 0.3048 0.381)
			(layers "F.Cu" "F.Mask" "F.Paste")
			(net "P5E_CPU0_G3_TX_DN<15>")
		)
	)
	(footprint ""
		(layer "F.Cu")
		(at 84.27212 -44.42206 -90)
		(property "Reference" "U207"
			(at 1.57734 -2.028952 90)
			(unlocked yes)
			(layer "F.SilkS")
			(effects
				(font
					(size 0.7874 0.5842)
					(thickness 0.1524)
				)
				(justify left)
			)
		)
		(property "Value" ""
			(at 0 0 270)
			(layer "F.Fab")
			(effects
				(font
					(size 1.27 1.27)
				)
			)
		)
		(duplicate_pad_numbers_are_jumpers no)
		(fp_line
			(start -1.695958 1.124966)
			(end -1.695958 -1.124966)
			(stroke
				(width 0.1524)
				(type default)
			)
			(layer "F.SilkS")
		)
		(fp_line
			(start 1.695958 1.124966)
			(end -1.695958 1.124966)
			(stroke
				(width 0.1524)
				(type default)
			)
			(layer "F.SilkS")
		)
		(fp_line
			(start -1.695958 -1.124966)
			(end 1.695958 -1.124966)
			(stroke
				(width 0.1524)
				(type default)
			)
			(layer "F.SilkS")
		)
		(fp_line
			(start 1.695958 -1.124966)
			(end 1.695958 1.124966)
			(stroke
				(width 0.1524)
				(type default)
			)
			(layer "F.SilkS")
		)
		(fp_poly
			(pts
				(xy -2.43332 -0.484886) (xy -2.43332 -1.104646) (xy -1.81356 -0.794766)
			)
			(stroke
				(width 0)
				(type default)
			)
			(fill yes)
			(layer "F.SilkS")
		)
		(fp_line
			(start -0.674878 1.124966)
			(end -0.674878 -1.124966)
			(stroke
				(width 0.1)
				(type default)
			)
			(layer "F.Fab")
		)
		(fp_line
			(start 0.674878 1.124966)
			(end -0.674878 1.124966)
			(stroke
				(width 0.1)
				(type default)
			)
			(layer "F.Fab")
		)
		(fp_line
			(start -0.674878 -1.124966)
			(end 0.674878 -1.124966)
			(stroke
				(width 0.1)
				(type default)
			)
			(layer "F.Fab")
		)
		(fp_line
			(start 0.674878 -1.124966)
			(end 0.674878 1.124966)
			(stroke
				(width 0.1)
				(type default)
			)
			(layer "F.Fab")
		)
		(fp_poly
			(pts
				(xy -2.4892 -0.959866) (xy -1.86944 -0.649986) (xy -2.4892 -0.340106)
			)
			(stroke
				(width 0)
				(type default)
			)
			(fill yes)
			(layer "F.Fab")
		)
		(pad "1" smd rect
			(at -0.94488 -0.649986)
			(size 0.3556 1.2446)
			(layers "F.Cu" "F.Mask" "F.Paste")
			(net "Net_10784")
		)
		(pad "2" smd rect
			(at -0.94488 0)
			(size 0.3556 1.2446)
			(layers "F.Cu" "F.Mask" "F.Paste")
			(net "RST_PERST_OCP_V3_2_BUF_N")
		)
		(pad "3" smd rect
			(at -0.94488 0.649986)
			(size 0.3556 1.2446)
			(layers "F.Cu" "F.Mask" "F.Paste")
			(net "GND")
		)
		(pad "4" smd rect
			(at 0.94488 0.649986)
			(size 0.3556 1.2446)
			(layers "F.Cu" "F.Mask" "F.Paste")
			(net "RST_PERST_OCP_V3_2_BUF2_N")
		)
		(pad "5" smd rect
			(at 0.94488 -0.649986)
			(size 0.3556 1.2446)
			(layers "F.Cu" "F.Mask" "F.Paste")
			(net "P3V3_AUX")
		)
	)
)
